# T6G (Grand Teton) — schematic netlist excerpt (pin names and nets, part order shuffled) for the footprints in the layout excerpt that follows; sources: Cadence DE-HDL packaged netlist, KiCad conversion of 04192023_DAF0TMB3IC0_F0TG_MB_C_brd_V02_OCP.brd

R1372  Q_RES  1K 1% CHIP  pkg 0201LF  page 331 : A = JTAG_TRST_RT_CPU1_P1_N ; B = GND
PC189  Q_CAP  560PF 50V 10% EMPTY  pkg C0402  page 201 : A = SW_PVDDCR_CPU1_P0_SW1 ; B = SW_PVDDCR_CPU1_P0_SW1_RC
PR3917  Q_RES  0 5% CHIP  pkg 0402LF  page 263 : A = HSC_SCREF ; B = HSC_SCREF_2

(kicad_pcb
	(version 20260206)
	(generator "pcbnew")
	(generator_version "10.0")
	(general
		(thickness 1.6)
		(legacy_teardrops no)
	)
	(paper "A4")
	(title_block
		(title "04192023_DAF0TMB3IC0_F0TG_MB_C_brd_V02_OCP.brd")
		(comment 1 "Grand Teton / footprints 2312-2314 of 8354")
	)
	(layers
		(0 "F.Cu" signal "TOP")
		(4 "In1.Cu" signal "GND")
		(6 "In2.Cu" signal "IN1")
		(8 "In3.Cu" signal "GND1")
		(10 "In4.Cu" signal "IN2")
		(12 "In5.Cu" signal "GND2")
		(14 "In6.Cu" signal "IN3")
		(16 "In7.Cu" signal "GND3")
		(18 "In8.Cu" signal "VCC")
		(20 "In9.Cu" signal "VCC1")
		(22 "In10.Cu" signal "GND4")
		(24 "In11.Cu" signal "IN4")
		(26 "In12.Cu" signal "GND5")
		(28 "In13.Cu" signal "IN5")
		(30 "In14.Cu" signal "GND6")
		(32 "In15.Cu" signal "IN6")
		(34 "In16.Cu" signal "GND7")
		(2 "B.Cu" signal "BOTTOM")
		(9 "F.Adhes" user "F.Adhesive")
		(11 "B.Adhes" user "B.Adhesive")
		(13 "F.Paste" user "Package Geometry/Pastemask Top")
		(15 "B.Paste" user "Package Geometry/Pastemask Bottom")
		(5 "F.SilkS" user "Ref Des/Silkscreen Top")
		(7 "B.SilkS" user "Ref Des/Silkscreen Bottom")
		(1 "F.Mask" user "Board Geometry/Soldermask Top")
		(3 "B.Mask" user "Board Geometry/Soldermask Bottom")
		(17 "Dwgs.User" user "User.Drawings")
		(19 "Cmts.User" user "User.Comments")
		(21 "Eco1.User" user "User.Eco1")
		(23 "Eco2.User" user "User.Eco2")
		(25 "Edge.Cuts" user "Board Geometry/Outline")
		(27 "Margin" user)
		(31 "F.CrtYd" user "Package Geometry/Place Bound Top")
		(29 "B.CrtYd" user "Package Geometry/Place Bound Bottom")
		(35 "F.Fab" user "Ref Des/Assembly Top")
		(33 "B.Fab" user "Ref Des/Assembly Bottom")
	)
	(footprint ""
		(layer "F.Cu")
		(at 204.7621 -408.084782)
		(property "Reference" "PR3917"
			(at 0 0 0)
			(layer "F.SilkS")
			(hide yes)
			(effects
				(font
					(size 1.27 1.27)
				)
			)
		)
		(property "Value" ""
			(at 0 0 0)
			(layer "F.Fab")
			(effects
				(font
					(size 1.27 1.27)
				)
			)
		)
		(duplicate_pad_numbers_are_jumpers no)
		(fp_line
			(start -0.7874 -0.4064)
			(end 0.7874 -0.4064)
			(stroke
				(width 0.1524)
				(type default)
			)
			(layer "F.SilkS")
		)
		(fp_line
			(start -0.7874 0.4064)
			(end -0.7874 -0.4064)
			(stroke
				(width 0.1524)
				(type default)
			)
			(layer "F.SilkS")
		)
		(fp_line
			(start 0.7874 -0.4064)
			(end 0.7874 0.4064)
			(stroke
				(width 0.1524)
				(type default)
			)
			(layer "F.SilkS")
		)
		(fp_line
			(start 0.7874 0.4064)
			(end -0.7874 0.4064)
			(stroke
				(width 0.1524)
				(type default)
			)
			(layer "F.SilkS")
		)
		(fp_line
			(start -0.67945 -0.305054)
			(end -0.12065 -0.305054)
			(stroke
				(width 0.1)
				(type default)
			)
			(layer "F.Fab")
		)
		(fp_line
			(start -0.67945 0.3048)
			(end -0.67945 -0.305054)
			(stroke
				(width 0.1)
				(type default)
			)
			(layer "F.Fab")
		)
		(fp_line
			(start -0.12065 -0.305054)
			(end -0.12065 -0.2794)
			(stroke
				(width 0.1)
				(type default)
			)
			(layer "F.Fab")
		)
		(fp_line
			(start -0.12065 -0.2794)
			(end 0.12065 -0.2794)
			(stroke
				(width 0.1)
				(type default)
			)
			(layer "F.Fab")
		)
		(fp_line
			(start -0.12065 0.2794)
			(end -0.12065 0.3048)
			(stroke
				(width 0.1)
				(type default)
			)
			(layer "F.Fab")
		)
		(fp_line
			(start -0.12065 0.3048)
			(end -0.67945 0.3048)
			(stroke
				(width 0.1)
				(type default)
			)
			(layer "F.Fab")
		)
		(fp_line
			(start 0.120396 0.2794)
			(end -0.12065 0.2794)
			(stroke
				(width 0.1)
				(type default)
			)
			(layer "F.Fab")
		)
		(fp_line
			(start 0.120396 0.3048)
			(end 0.120396 0.2794)
			(stroke
				(width 0.1)
				(type default)
			)
			(layer "F.Fab")
		)
		(fp_line
			(start 0.12065 -0.3048)
			(end 0.67945 -0.3048)
			(stroke
				(width 0.1)
				(type default)
			)
			(layer "F.Fab")
		)
		(fp_line
			(start 0.12065 -0.2794)
			(end 0.12065 -0.3048)
			(stroke
				(width 0.1)
				(type default)
			)
			(layer "F.Fab")
		)
		(fp_line
			(start 0.67945 -0.3048)
			(end 0.67945 0.3048)
			(stroke
				(width 0.1)
				(type default)
			)
			(layer "F.Fab")
		)
		(fp_line
			(start 0.67945 0.3048)
			(end 0.120396 0.3048)
			(stroke
				(width 0.1)
				(type default)
			)
			(layer "F.Fab")
		)
		(pad "1" smd circle
			(at -0.40005 0)
			(size 0 0)
			(layers "F.Cu" "F.Mask" "F.Paste")
			(net "HSC_SCREF")
		)
		(pad "2" smd circle
			(at 0.40005 0)
			(size 0 0)
			(layers "F.Cu" "F.Mask" "F.Paste")
			(net "HSC_SCREF_2")
		)
	)
	(footprint ""
		(layer "F.Cu")
		(at 104.1908 -392.2268)
		(property "Reference" "R1372"
			(at 0 0 0)
			(layer "F.SilkS")
			(hide yes)
			(effects
				(font
					(size 1.27 1.27)
				)
			)
		)
		(property "Value" ""
			(at 0 0 0)
			(layer "F.Fab")
			(effects
				(font
					(size 1.27 1.27)
				)
			)
		)
		(duplicate_pad_numbers_are_jumpers no)
		(fp_line
			(start -0.32512 -0.175006)
			(end 0.32512 -0.175006)
			(stroke
				(width 0.1)
				(type default)
			)
			(layer "F.Fab")
		)
		(fp_line
			(start -0.32512 0.175006)
			(end -0.32512 -0.175006)
			(stroke
				(width 0.1)
				(type default)
			)
			(layer "F.Fab")
		)
		(fp_line
			(start 0.32512 -0.175006)
			(end 0.32512 0.175006)
			(stroke
				(width 0.1)
				(type default)
			)
			(layer "F.Fab")
		)
		(fp_line
			(start 0.32512 0.175006)
			(end -0.32512 0.175006)
			(stroke
				(width 0.1)
				(type default)
			)
			(layer "F.Fab")
		)
		(pad "1" smd rect
			(at -0.2667 0)
			(size 0.3048 0.381)
			(layers "F.Cu" "F.Mask" "F.Paste")
			(net "JTAG_TRST_RT_CPU1_P1_N")
		)
		(pad "2" smd rect
			(at 0.2667 0 180)
			(size 0.3048 0.381)
			(layers "F.Cu" "F.Mask" "F.Paste")
			(net "GND")
		)
	)
	(footprint ""
		(layer "F.Cu")
		(at 331.365098 -331.969364 180)
		(property "Reference" "PC189"
			(at 0 0 180)
			(layer "F.SilkS")
			(hide yes)
			(effects
				(font
					(size 1.27 1.27)
				)
			)
		)
		(property "Value" ""
			(at 0 0 180)
			(layer "F.Fab")
			(effects
				(font
					(size 1.27 1.27)
				)
			)
		)
		(duplicate_pad_numbers_are_jumpers no)
		(fp_line
			(start 0.7874 0.4064)
			(end -0.7874 0.4064)
			(stroke
				(width 0.1524)
				(type default)
			)
			(layer "F.SilkS")
		)
		(fp_line
			(start 0.7874 -0.4064)
			(end 0.7874 0.4064)
			(stroke
				(width 0.1524)
				(type default)
			)
			(layer "F.SilkS")
		)
		(fp_line
			(start -0.7874 0.4064)
			(end -0.7874 -0.4064)
			(stroke
				(width 0.1524)
				(type default)
			)
			(layer "F.SilkS")
		)
		(fp_line
			(start -0.7874 -0.4064)
			(end 0.7874 -0.4064)
			(stroke
				(width 0.1524)
				(type default)
			)
			(layer "F.SilkS")
		)
		(fp_line
			(start 0.67945 0.3048)
			(end 0.120396 0.3048)
			(stroke
				(width 0.1)
				(type default)
			)
			(layer "F.Fab")
		)
		(fp_line
			(start 0.67945 -0.3048)
			(end 0.67945 0.3048)
			(stroke
				(width 0.1)
				(type default)
			)
			(layer "F.Fab")
		)
		(fp_line
			(start 0.12065 -0.2794)
			(end 0.12065 -0.3048)
			(stroke
				(width 0.1)
				(type default)
			)
			(layer "F.Fab")
		)
		(fp_line
			(start 0.12065 -0.3048)
			(end 0.67945 -0.3048)
			(stroke
				(width 0.1)
				(type default)
			)
			(layer "F.Fab")
		)
		(fp_line
			(start 0.120396 0.3048)
			(end 0.120396 0.2794)
			(stroke
				(width 0.1)
				(type default)
			)
			(layer "F.Fab")
		)
		(fp_line
			(start 0.120396 0.2794)
			(end -0.12065 0.2794)
			(stroke
				(width 0.1)
				(type default)
			)
			(layer "F.Fab")
		)
		(fp_line
			(start -0.12065 0.3048)
			(end -0.67945 0.3048)
			(stroke
				(width 0.1)
				(type default)
			)
			(layer "F.Fab")
		)
		(fp_line
			(start -0.12065 0.2794)
			(end -0.12065 0.3048)
			(stroke
				(width 0.1)
				(type default)
			)
			(layer "F.Fab")
		)
		(fp_line
			(start -0.12065 -0.2794)
			(end 0.12065 -0.2794)
			(stroke
				(width 0.1)
				(type default)
			)
			(layer "F.Fab")
		)
		(fp_line
			(start -0.12065 -0.305054)
			(end -0.12065 -0.2794)
			(stroke
				(width 0.1)
				(type default)
			)
			(layer "F.Fab")
		)
		(fp_line
			(start -0.67945 0.3048)
			(end -0.67945 -0.305054)
			(stroke
				(width 0.1)
				(type default)
			)
			(layer "F.Fab")
		)
		(fp_line
			(start -0.67945 -0.305054)
			(end -0.12065 -0.305054)
			(stroke
				(width 0.1)
				(type default)
			)
			(layer "F.Fab")
		)
		(pad "1" smd circle
			(at -0.40005 0 180)
			(size 0 0)
			(layers "F.Cu" "F.Mask" "F.Paste")
			(net "SW_PVDDCR_CPU1_P0_SW1")
		)
		(pad "2" smd circle
			(at 0.40005 0 180)
			(size 0 0)
			(layers "F.Cu" "F.Mask" "F.Paste")
			(net "SW_PVDDCR_CPU1_P0_SW1_RC")
		)
	)
)
